FILE_TYPE = CONNECTIVITY;
{Allegro Design Entry HDL 17.2-2016 S081 (4005846) 1/11/2022}
"PAGE_NUMBER" = 96;
0"NC";
1"P3V3_AUX\g";
2"P12V_S3_AUX_CPU0_NVDIMM\g";
3"P12V_S3_AUX_CPU0_NVDIMM\g";
4"P3V3_AUX\g";
5"GND\g";
6"GND\g";
7"GND\g";
8"GND\g";
9"GND\g";
10"M_H_CPU0_SA_CB<7:0>";
11"M_H_CPU0_SB_CB<7:0>";
12"M_H_CPU0_SA_CA<6:0>";
13"M_H_CPU0_SB_CA<6:0>";
14"M_H_CPU0_SA_DQ<31:0>";
15"M_H_CPU0_SB_DQ<31:0>";
16"M_H_CPU0_SB_DQS_DP<9:0>";
17"M_H_CPU0_SA_DQS_DP<9:0>";
18"M_H_CPU0_SB_DQS_DN<9:0>";
19"M_H_CPU0_SA_DQS_DN<9:0>";
20"M_H_CPU0_SB_DQ<29>";
21"M_H_CPU0_CLK_DN<0>";
22"M_H_CPU0_ALERT_N";
23"PD_CHH_CPU0_DIMM1_SAA";
24"I3C_SPD_DDREFGH_CPU0_LVC1_SDA";
25"I3C_SPD_DDREFGH_CPU0_LVC1_SCL_R7";
26"RST_M_GH_CPU0_FPGA_N";
27"I3C_SPD_DDREFGH_CPU0_LVC1_SCL";
28"PWRGD_CHH_CPU0_DIMM1";
29"TP_CHH_CPU0_DIMM1_FRU_6";
30"M_H_CPU0_SB_CB<1>";
31"M_H_CPU0_SA_DQS_DN<9>";
32"M_H_CPU0_SA_DQS_DN<8>";
33"M_H_CPU0_SA_DQS_DN<7>";
34"M_H_CPU0_SA_DQS_DN<6>";
35"M_H_CPU0_SA_DQS_DN<5>";
36"M_H_CPU0_SA_DQS_DN<4>";
37"M_H_CPU0_SA_DQS_DN<2>";
38"M_H_CPU0_SA_DQS_DN<3>";
39"M_H_CPU0_SA_DQS_DN<1>";
40"M_H_CPU0_SA_DQS_DN<0>";
41"M_H_CPU0_SB_DQS_DN<9>";
42"M_H_CPU0_SB_DQS_DN<8>";
43"M_H_CPU0_SB_DQS_DN<6>";
44"M_H_CPU0_SB_DQS_DN<7>";
45"M_H_CPU0_SB_DQS_DN<5>";
46"M_H_CPU0_SB_DQS_DN<4>";
47"M_H_CPU0_SB_DQS_DN<3>";
48"M_H_CPU0_SB_DQS_DN<1>";
49"M_H_CPU0_SB_DQS_DN<2>";
50"M_H_CPU0_SB_DQS_DN<0>";
51"M_H_CPU0_SA_DQS_DP<9>";
52"M_H_CPU0_SA_DQS_DP<8>";
53"M_H_CPU0_SA_DQS_DP<7>";
54"M_H_CPU0_SA_DQS_DP<6>";
55"M_H_CPU0_SA_DQS_DP<5>";
56"M_H_CPU0_SA_DQS_DP<4>";
57"M_H_CPU0_SA_DQS_DP<3>";
58"M_H_CPU0_SA_DQS_DP<2>";
59"M_H_CPU0_SA_DQS_DP<1>";
60"M_H_CPU0_SA_DQS_DP<0>";
61"M_H_CPU0_SB_DQS_DP<9>";
62"M_H_CPU0_SB_DQS_DP<8>";
63"M_H_CPU0_SB_DQS_DP<7>";
64"M_H_CPU0_SB_DQS_DP<6>";
65"M_H_CPU0_SB_DQS_DP<5>";
66"M_H_CPU0_SB_DQS_DP<4>";
67"M_H_CPU0_SB_DQS_DP<3>";
68"M_H_CPU0_SB_DQS_DP<2>";
69"M_H_CPU0_SB_DQS_DP<1>";
70"M_H_CPU0_SB_DQS_DP<0>";
71"M_H_CPU0_SB_CB<4>";
72"M_H_CPU0_SA_DQ<31>";
73"M_H_CPU0_SA_DQ<28>";
74"M_H_CPU0_SA_DQ<19>";
75"M_H_CPU0_SA_DQ<4>";
76"M_H_CPU0_SA_CB<6>";
77"M_H_CPU0_SA_DQ<9>";
78"M_H_CPU0_SA_DQ<10>";
79"M_H_CPU0_SA_DQ<14>";
80"M_H_CPU0_SA_DQ<13>";
81"M_H_CPU0_SA_DQ<3>";
82"M_H_CPU0_SA_DQ<2>";
83"M_H_CPU0_SA_DQ<1>";
84"M_H_CPU0_SB_DQ<30>";
85"TP_CHH_CPU0_DIMM1_FRU_0";
86"TP_CHH_CPU0_DIMM1_FRU_1";
87"TP_CHH_CPU0_DIMM1_FRU_2";
88"TP_CHH_CPU0_DIMM1_FRU_3";
89"TP_CHH_CPU0_DIMM1_FRU_4";
90"TP_CHH_CPU0_DIMM1_FRU_5";
91"M_H_CPU0_SB_PAR";
92"M_H_CPU0_SA_PAR";
93"M_H_CPU0_SB_RSP<0>";
94"M_H_CPU0_SA_RSP<0>";
95"M_H_CPU0_SB_DQ<0>";
96"M_H_CPU0_SB_DQ<1>";
97"M_H_CPU0_SB_DQ<2>";
98"M_H_CPU0_SB_DQ<3>";
99"M_H_CPU0_SB_DQ<4>";
100"M_H_CPU0_SB_DQ<5>";
101"M_H_CPU0_SB_DQ<6>";
102"M_H_CPU0_SB_DQ<7>";
103"M_H_CPU0_SB_DQ<8>";
104"M_H_CPU0_SB_DQ<9>";
105"M_H_CPU0_SB_DQ<10>";
106"M_H_CPU0_SB_DQ<11>";
107"M_H_CPU0_SB_DQ<12>";
108"M_H_CPU0_SB_DQ<13>";
109"M_H_CPU0_SB_DQ<14>";
110"M_H_CPU0_SB_DQ<15>";
111"M_H_CPU0_SB_DQ<16>";
112"M_H_CPU0_SB_DQ<17>";
113"M_H_CPU0_SB_DQ<18>";
114"M_H_CPU0_SB_DQ<19>";
115"M_H_CPU0_SB_DQ<20>";
116"M_H_CPU0_SB_DQ<21>";
117"M_H_CPU0_SB_DQ<22>";
118"M_H_CPU0_SB_DQ<23>";
119"M_H_CPU0_SB_DQ<24>";
120"M_H_CPU0_SB_DQ<25>";
121"M_H_CPU0_SB_DQ<26>";
122"M_H_CPU0_SB_DQ<27>";
123"M_H_CPU0_SB_DQ<28>";
124"M_H_CPU0_SB_DQ<31>";
125"M_H_CPU0_SA_DQ<0>";
126"M_H_CPU0_SA_DQ<5>";
127"M_H_CPU0_SA_DQ<6>";
128"M_H_CPU0_SA_DQ<7>";
129"M_H_CPU0_SA_DQ<8>";
130"M_H_CPU0_SA_DQ<11>";
131"M_H_CPU0_SA_DQ<12>";
132"M_H_CPU0_SA_DQ<15>";
133"M_H_CPU0_SA_DQ<16>";
134"M_H_CPU0_SA_DQ<17>";
135"M_H_CPU0_SA_DQ<18>";
136"M_H_CPU0_SA_DQ<20>";
137"M_H_CPU0_SA_DQ<21>";
138"M_H_CPU0_SA_DQ<22>";
139"M_H_CPU0_SA_DQ<23>";
140"M_H_CPU0_SA_DQ<24>";
141"M_H_CPU0_SA_DQ<25>";
142"M_H_CPU0_SA_DQ<26>";
143"M_H_CPU0_SA_DQ<27>";
144"M_H_CPU0_SA_DQ<29>";
145"M_H_CPU0_SA_DQ<30>";
146"M_H_CPU0_SB_CS_N<1>";
147"M_H_CPU0_SA_CS_N<1>";
148"M_H_CPU0_SB_CS_N<0>";
149"M_H_CPU0_SA_CS_N<0>";
150"M_H_CPU0_CLK_DP<0>";
151"M_H_CPU0_SB_CB<0>";
152"M_H_CPU0_SB_CB<2>";
153"M_H_CPU0_SB_CB<3>";
154"M_H_CPU0_SB_CB<5>";
155"M_H_CPU0_SB_CB<6>";
156"M_H_CPU0_SA_CB<0>";
157"M_H_CPU0_SA_CB<2>";
158"M_H_CPU0_SA_CB<3>";
159"M_H_CPU0_SA_CB<5>";
160"M_H_CPU0_SB_CA<6>";
161"M_H_CPU0_SA_CA<6>";
162"M_H_CPU0_SB_CA<5>";
163"M_H_CPU0_SA_CA<5>";
164"M_H_CPU0_SB_CA<4>";
165"M_H_CPU0_SA_CA<4>";
166"M_H_CPU0_SB_CA<3>";
167"M_H_CPU0_SA_CA<3>";
168"M_H_CPU0_SB_CA<2>";
169"M_H_CPU0_SA_CA<2>";
170"M_H_CPU0_SB_CA<1>";
171"M_H_CPU0_SA_CA<1>";
172"M_H_CPU0_SB_CA<0>";
173"M_H_CPU0_SA_CA<0>";
174"M_H_CPU0_SB_CB<7>";
175"M_H_CPU0_SA_CB<1>";
176"M_H_CPU0_SA_CB<4>";
177"M_H_CPU0_SA_CB<7>";
178"PD_CHH_CPU0_DIMM1_SAA";
%"UNIVERSAL_GND"
"1","(-2275,-400)","0","logical_power","I1";
;
CDS_LIB"logical_power"
HDL_POWER"GND";
"A"9;
%"TAP"
"1","(-850,3425)","0","standard","I100";
;
CDS_LIB"standard"
BODY_TYPE"PLUMBING"
HDL_TAP"TRUE";
"B \NAC \NWC"14;
"S \NAC"
BN"20"136;
%"TAP"
"1","(-850,3375)","0","standard","I101";
;
CDS_LIB"standard"
BODY_TYPE"PLUMBING"
HDL_TAP"TRUE";
"B \NAC \NWC"14;
"S \NAC"
BN"19"74;
%"TAP"
"1","(-850,3475)","0","standard","I102";
;
CDS_LIB"standard"
BODY_TYPE"PLUMBING"
HDL_TAP"TRUE";
"B \NAC \NWC"14;
"S \NAC"
BN"21"137;
%"TAP"
"1","(-850,3525)","0","standard","I103";
;
CDS_LIB"standard"
BODY_TYPE"PLUMBING"
HDL_TAP"TRUE";
"B \NAC \NWC"14;
"S \NAC"
BN"22"138;
%"TAP"
"1","(-850,3575)","0","standard","I104";
;
CDS_LIB"standard"
BODY_TYPE"PLUMBING"
HDL_TAP"TRUE";
"B \NAC \NWC"14;
"S \NAC"
BN"23"139;
%"TAP"
"1","(-850,3675)","0","standard","I105";
;
CDS_LIB"standard"
BODY_TYPE"PLUMBING"
HDL_TAP"TRUE";
"B \NAC \NWC"14;
"S \NAC"
BN"25"141;
%"TAP"
"1","(-850,3625)","0","standard","I106";
;
CDS_LIB"standard"
BODY_TYPE"PLUMBING"
HDL_TAP"TRUE";
"B \NAC \NWC"14;
"S \NAC"
BN"24"140;
%"TAP"
"1","(-2500,3775)","2","standard","I108";
;
CDS_LIB"standard"
BODY_TYPE"PLUMBING"
HDL_TAP"TRUE";
"B \NAC \NWC"12;
"S \NAC"
BN"2"169;
%"TAP"
"1","(-2500,3725)","2","standard","I109";
;
CDS_LIB"standard"
BODY_TYPE"PLUMBING"
HDL_TAP"TRUE";
"B \NAC \NWC"12;
"S \NAC"
BN"1"171;
%"TAP"
"1","(-2500,3825)","2","standard","I110";
;
CDS_LIB"standard"
BODY_TYPE"PLUMBING"
HDL_TAP"TRUE";
"B \NAC \NWC"12;
"S \NAC"
BN"3"167;
%"TAP"
"1","(-2500,3925)","2","standard","I111";
;
CDS_LIB"standard"
BODY_TYPE"PLUMBING"
HDL_TAP"TRUE";
"B \NAC \NWC"12;
"S \NAC"
BN"5"163;
%"TAP"
"1","(-2500,3875)","2","standard","I112";
;
CDS_LIB"standard"
BODY_TYPE"PLUMBING"
HDL_TAP"TRUE";
"B \NAC \NWC"12;
"S \NAC"
BN"4"165;
%"TAP"
"1","(-2500,3975)","2","standard","I113";
;
CDS_LIB"standard"
BODY_TYPE"PLUMBING"
HDL_TAP"TRUE";
"B \NAC \NWC"12;
"S \NAC"
BN"6"161;
%"TAP"
"1","(-850,3775)","0","standard","I114";
;
CDS_LIB"standard"
BODY_TYPE"PLUMBING"
HDL_TAP"TRUE";
"B \NAC \NWC"14;
"S \NAC"
BN"27"143;
%"TAP"
"1","(-850,3725)","0","standard","I115";
;
CDS_LIB"standard"
BODY_TYPE"PLUMBING"
HDL_TAP"TRUE";
"B \NAC \NWC"14;
"S \NAC"
BN"26"142;
%"TAP"
"1","(-850,3825)","0","standard","I116";
;
CDS_LIB"standard"
BODY_TYPE"PLUMBING"
HDL_TAP"TRUE";
"B \NAC \NWC"14;
"S \NAC"
BN"28"73;
%"TAP"
"1","(-850,3875)","0","standard","I117";
;
CDS_LIB"standard"
BODY_TYPE"PLUMBING"
HDL_TAP"TRUE";
"B \NAC \NWC"14;
"S \NAC"
BN"29"144;
%"TAP"
"1","(-850,3975)","0","standard","I118";
;
CDS_LIB"standard"
BODY_TYPE"PLUMBING"
HDL_TAP"TRUE";
"B \NAC \NWC"14;
"S \NAC"
BN"31"72;
%"TAP"
"1","(-850,3925)","0","standard","I119";
;
CDS_LIB"standard"
BODY_TYPE"PLUMBING"
HDL_TAP"TRUE";
"B \NAC \NWC"14;
"S \NAC"
BN"30"145;
%"UNIVERSAL_GND"
"1","(875,-275)","0","logical_power","I120";
;
CDS_LIB"logical_power"
HDL_POWER"GND";
"A"8;
%"Q_CAP"
"1","(875,100)","0","pure_quanta","I121";
;
PART_NUMBER"CH5221MEB00"
PACK_TYPE"C0402"
MATERIAL"X6S"
TOLERANCE"20%"
VOLTAGE"6.3V"
VALUE"2.2UF"
$LOCATION"C44"
CDS_LIB"pure_quanta"
CDS_LOCATION"C44"
$SEC"1"
CDS_SEC"1";
"B"
$PN"2"8;
"A"
$PN"1"4;
%"VCC_CORE"
"1","(875,425)","0","logical_power","I122";
;
HDL_POWER"P3V3_AUX"
CDS_LIB"logical_power";
"A"4;
%"Q_CAP"
"1","(1875,100)","0","pure_quanta","I125";
;
PART_NUMBER"CH6103KEA00"
PACK_TYPE"C0805"
TOLERANCE"10%"
VOLTAGE"16V"
VALUE"10UF"
MATERIAL"X6S"
$LOCATION"C45"
CDS_LIB"pure_quanta"
CDS_LOCATION"C45"
$SEC"1"
CDS_SEC"1";
"B"
$PN"2"7;
"A"
$PN"1"3;
%"VCC_CORE"
"1","(1875,425)","0","logical_power","I126";
;
HDL_POWER"P12V_S3_AUX_CPU0_NVDIMM"
CDS_LIB"logical_power";
"A"3;
%"Q_CAP"
"1","(2500,100)","0","pure_quanta","I127";
;
PART_NUMBER"CH6103KEA00"
PACK_TYPE"C0805"
VALUE"10UF"
VOLTAGE"16V"
TOLERANCE"10%"
MATERIAL"X6S"
$LOCATION"C46"
CDS_LIB"pure_quanta"
CDS_LOCATION"C46"
$SEC"1"
CDS_SEC"1";
"B"
$PN"2"7;
"A"
$PN"1"3;
%"UNIVERSAL_GND"
"1","(2500,-275)","0","logical_power","I128";
;
CDS_LIB"logical_power"
HDL_POWER"GND";
"A"7;
%"UNIVERSAL_GND"
"1","(3575,275)","0","logical_power","I129";
;
CDS_LIB"logical_power"
HDL_POWER"GND";
"A"6;
%"TAP"
"1","(1900,2125)","0","standard","I130";
;
CDS_LIB"standard"
BODY_TYPE"PLUMBING"
HDL_TAP"TRUE";
"B \NAC \NWC"16;
"S \NAC"
BN"1"69;
%"TAP"
"1","(1900,2025)","0","standard","I131";
;
CDS_LIB"standard"
BODY_TYPE"PLUMBING"
HDL_TAP"TRUE";
"B \NAC \NWC"16;
"S \NAC"
BN"0"70;
%"TAP"
"1","(2075,1975)","0","standard","I132";
;
CDS_LIB"standard"
BODY_TYPE"PLUMBING"
HDL_TAP"TRUE";
"B \NAC \NWC"18;
"S \NAC"
BN"0"50;
%"TAP"
"1","(2075,2075)","0","standard","I133";
;
CDS_LIB"standard"
BODY_TYPE"PLUMBING"
HDL_TAP"TRUE";
"B \NAC \NWC"18;
"S \NAC"
BN"1"48;
%"TAP"
"1","(2075,2175)","0","standard","I134";
;
CDS_LIB"standard"
BODY_TYPE"PLUMBING"
HDL_TAP"TRUE";
"B \NAC \NWC"18;
"S \NAC"
BN"2"49;
%"TAP"
"1","(1900,2225)","0","standard","I135";
;
CDS_LIB"standard"
BODY_TYPE"PLUMBING"
HDL_TAP"TRUE";
"B \NAC \NWC"16;
"S \NAC"
BN"2"68;
%"TAP"
"1","(1900,2325)","0","standard","I136";
;
CDS_LIB"standard"
BODY_TYPE"PLUMBING"
HDL_TAP"TRUE";
"B \NAC \NWC"16;
"S \NAC"
BN"3"67;
%"TAP"
"1","(1900,2425)","0","standard","I137";
;
CDS_LIB"standard"
BODY_TYPE"PLUMBING"
HDL_TAP"TRUE";
"B \NAC \NWC"16;
"S \NAC"
BN"4"66;
%"TAP"
"1","(2075,2275)","0","standard","I138";
;
CDS_LIB"standard"
BODY_TYPE"PLUMBING"
HDL_TAP"TRUE";
"B \NAC \NWC"18;
"S \NAC"
BN"3"47;
%"TAP"
"1","(2075,2375)","0","standard","I139";
;
CDS_LIB"standard"
BODY_TYPE"PLUMBING"
HDL_TAP"TRUE";
"B \NAC \NWC"18;
"S \NAC"
BN"4"46;
%"TAP"
"1","(1900,2625)","0","standard","I140";
;
CDS_LIB"standard"
BODY_TYPE"PLUMBING"
HDL_TAP"TRUE";
"B \NAC \NWC"16;
"S \NAC"
BN"6"64;
%"TAP"
"1","(1900,2525)","0","standard","I141";
;
CDS_LIB"standard"
BODY_TYPE"PLUMBING"
HDL_TAP"TRUE";
"B \NAC \NWC"16;
"S \NAC"
BN"5"65;
%"TAP"
"1","(2075,2575)","0","standard","I142";
;
CDS_LIB"standard"
BODY_TYPE"PLUMBING"
HDL_TAP"TRUE";
"B \NAC \NWC"18;
"S \NAC"
BN"6"43;
%"TAP"
"1","(2075,2675)","0","standard","I143";
;
CDS_LIB"standard"
BODY_TYPE"PLUMBING"
HDL_TAP"TRUE";
"B \NAC \NWC"18;
"S \NAC"
BN"7"44;
%"TAP"
"1","(2075,2475)","0","standard","I144";
;
CDS_LIB"standard"
BODY_TYPE"PLUMBING"
HDL_TAP"TRUE";
"B \NAC \NWC"18;
"S \NAC"
BN"5"45;
%"TAP"
"1","(1900,2725)","0","standard","I145";
;
CDS_LIB"standard"
BODY_TYPE"PLUMBING"
HDL_TAP"TRUE";
"B \NAC \NWC"16;
"S \NAC"
BN"7"63;
%"TAP"
"1","(1900,2825)","0","standard","I146";
;
CDS_LIB"standard"
BODY_TYPE"PLUMBING"
HDL_TAP"TRUE";
"B \NAC \NWC"16;
"S \NAC"
BN"8"62;
%"TAP"
"1","(1900,2925)","0","standard","I147";
;
CDS_LIB"standard"
BODY_TYPE"PLUMBING"
HDL_TAP"TRUE";
"B \NAC \NWC"16;
"S \NAC"
BN"9"61;
%"TAP"
"1","(2075,2775)","0","standard","I148";
;
CDS_LIB"standard"
BODY_TYPE"PLUMBING"
HDL_TAP"TRUE";
"B \NAC \NWC"18;
"S \NAC"
BN"8"42;
%"TAP"
"1","(2075,2875)","0","standard","I149";
;
CDS_LIB"standard"
BODY_TYPE"PLUMBING"
HDL_TAP"TRUE";
"B \NAC \NWC"18;
"S \NAC"
BN"9"41;
%"TAP"
"1","(1900,3075)","0","standard","I150";
;
CDS_LIB"standard"
BODY_TYPE"PLUMBING"
HDL_TAP"TRUE";
"B \NAC \NWC"17;
"S \NAC"
BN"0"60;
%"TAP"
"1","(1900,3175)","0","standard","I151";
;
CDS_LIB"standard"
BODY_TYPE"PLUMBING"
HDL_TAP"TRUE";
"B \NAC \NWC"17;
"S \NAC"
BN"1"59;
%"TAP"
"1","(2075,3025)","0","standard","I152";
;
CDS_LIB"standard"
BODY_TYPE"PLUMBING"
HDL_TAP"TRUE";
"B \NAC \NWC"19;
"S \NAC"
BN"0"40;
%"TAP"
"1","(2075,3125)","0","standard","I153";
;
CDS_LIB"standard"
BODY_TYPE"PLUMBING"
HDL_TAP"TRUE";
"B \NAC \NWC"19;
"S \NAC"
BN"1"39;
%"TAP"
"1","(1900,3275)","0","standard","I154";
;
CDS_LIB"standard"
BODY_TYPE"PLUMBING"
HDL_TAP"TRUE";
"B \NAC \NWC"17;
"S \NAC"
BN"2"58;
%"TAP"
"1","(1900,3375)","0","standard","I155";
;
CDS_LIB"standard"
BODY_TYPE"PLUMBING"
HDL_TAP"TRUE";
"B \NAC \NWC"17;
"S \NAC"
BN"3"57;
%"TAP"
"1","(2075,3225)","0","standard","I156";
;
CDS_LIB"standard"
BODY_TYPE"PLUMBING"
HDL_TAP"TRUE";
"B \NAC \NWC"19;
"S \NAC"
BN"2"37;
%"TAP"
"1","(2075,3325)","0","standard","I157";
;
CDS_LIB"standard"
BODY_TYPE"PLUMBING"
HDL_TAP"TRUE";
"B \NAC \NWC"19;
"S \NAC"
BN"3"38;
%"TAP"
"1","(2075,3425)","0","standard","I158";
;
CDS_LIB"standard"
BODY_TYPE"PLUMBING"
HDL_TAP"TRUE";
"B \NAC \NWC"19;
"S \NAC"
BN"4"36;
%"TAP"
"1","(1900,3475)","0","standard","I159";
;
CDS_LIB"standard"
BODY_TYPE"PLUMBING"
HDL_TAP"TRUE";
"B \NAC \NWC"17;
"S \NAC"
BN"4"56;
%"TAP"
"1","(1900,3575)","0","standard","I160";
;
CDS_LIB"standard"
BODY_TYPE"PLUMBING"
HDL_TAP"TRUE";
"B \NAC \NWC"17;
"S \NAC"
BN"5"55;
%"TAP"
"1","(1900,3675)","0","standard","I161";
;
CDS_LIB"standard"
BODY_TYPE"PLUMBING"
HDL_TAP"TRUE";
"B \NAC \NWC"17;
"S \NAC"
BN"6"54;
%"TAP"
"1","(2075,3625)","0","standard","I162";
;
CDS_LIB"standard"
BODY_TYPE"PLUMBING"
HDL_TAP"TRUE";
"B \NAC \NWC"19;
"S \NAC"
BN"6"34;
%"TAP"
"1","(2075,3525)","0","standard","I163";
;
CDS_LIB"standard"
BODY_TYPE"PLUMBING"
HDL_TAP"TRUE";
"B \NAC \NWC"19;
"S \NAC"
BN"5"35;
%"TAP"
"1","(1900,3775)","0","standard","I167";
;
CDS_LIB"standard"
BODY_TYPE"PLUMBING"
HDL_TAP"TRUE";
"B \NAC \NWC"17;
"S \NAC"
BN"7"53;
%"TAP"
"1","(1900,3975)","0","standard","I168";
;
CDS_LIB"standard"
BODY_TYPE"PLUMBING"
HDL_TAP"TRUE";
"B \NAC \NWC"17;
"S \NAC"
BN"9"51;
%"TAP"
"1","(1900,3875)","0","standard","I169";
;
CDS_LIB"standard"
BODY_TYPE"PLUMBING"
HDL_TAP"TRUE";
"B \NAC \NWC"17;
"S \NAC"
BN"8"52;
%"TAP"
"1","(2075,3725)","0","standard","I170";
;
CDS_LIB"standard"
BODY_TYPE"PLUMBING"
HDL_TAP"TRUE";
"B \NAC \NWC"19;
"S \NAC"
BN"7"33;
%"TAP"
"1","(2075,3825)","0","standard","I171";
;
CDS_LIB"standard"
BODY_TYPE"PLUMBING"
HDL_TAP"TRUE";
"B \NAC \NWC"19;
"S \NAC"
BN"8"32;
%"TAP"
"1","(2075,3925)","0","standard","I172";
;
CDS_LIB"standard"
BODY_TYPE"PLUMBING"
HDL_TAP"TRUE";
"B \NAC \NWC"19;
"S \NAC"
BN"9"31;
%"VCC_CORE"
"1","(3575,4525)","0","logical_power","I175";
;
HDL_POWER"P12V_S3_AUX_CPU0_NVDIMM"
CDS_LIB"logical_power";
"A"2;
%"SCONN288_ADR50017P130CC"
"3","(4425,2350)","0","pure_quanta","I176";
;
PART_NUMBER"DFHST8FS461"
MATERIAL"IO"
VALUE"SCONN288_ADR50017-P130CC"
PART_TYPE"SMLF"
$LOCATION"J15"
NEEDS_NO_SIZE"TRUE"
CDS_LMAN_SYM_OUTLINE"-450,1775,450,-1775"
CDS_LIB"pure_quanta"
CDS_LOCATION"J15"
$SEC"3"
CDS_SEC"3";
"G3"
$PN"G3"5;
"G2"
$PN"G2"5;
"G1"
$PN"G1"5;
"VSS62"
$PN"141"5;
"VSS61"
$PN"139"5;
"VSS60"
$PN"136"5;
"VSS58"
$PN"132"5;
"VSS104"
$PN"240"6;
"VSS102"
$PN"235"6;
"VSS100"
$PN"230"6;
"VIN_BULK2"
$PN"146"2;
"VIN_BULK1"
$PN"145"2;
"VIN_BULK0"
$PN"1"2;
"VSS126"
$PN"288"6;
"VSS125"
$PN"286"6;
"VSS124"
$PN"284"6;
"VSS123"
$PN"281"6;
"VSS122"
$PN"279"6;
"VSS121"
$PN"277"6;
"VSS120"
$PN"275"6;
"VSS119"
$PN"273"6;
"VSS118"
$PN"270"6;
"VSS117"
$PN"268"6;
"VSS116"
$PN"266"6;
"VSS115"
$PN"264"6;
"VSS114"
$PN"262"6;
"VSS113"
$PN"259"6;
"VSS112"
$PN"257"6;
"VSS111"
$PN"255"6;
"VSS110"
$PN"253"6;
"VSS109"
$PN"251"6;
"VSS108"
$PN"248"6;
"VSS107"
$PN"246"6;
"VSS106"
$PN"244"6;
"VSS105"
$PN"242"6;
"VSS103"
$PN"237"6;
"VSS101"
$PN"233"6;
"VSS99"
$PN"228"6;
"VSS98"
$PN"226"6;
"VSS97"
$PN"224"6;
"VSS96"
$PN"222"6;
"VSS95"
$PN"219"6;
"VSS94"
$PN"216"6;
"VSS93"
$PN"214"6;
"VSS92"
$PN"212"6;
"VSS91"
$PN"210"6;
"VSS90"
$PN"208"6;
"VSS89"
$PN"206"6;
"VSS88"
$PN"204"6;
"VSS87"
$PN"202"6;
"VSS86"
$PN"199"6;
"VSS85"
$PN"197"6;
"VSS84"
$PN"195"6;
"VSS83"
$PN"193"6;
"VSS82"
$PN"191"6;
"VSS81"
$PN"188"6;
"VSS80"
$PN"186"6;
"VSS79"
$PN"184"6;
"VSS78"
$PN"182"6;
"VSS77"
$PN"180"6;
"VSS76"
$PN"177"6;
"VSS75"
$PN"175"6;
"VSS74"
$PN"173"6;
"VSS73"
$PN"171"6;
"VSS72"
$PN"169"6;
"VSS71"
$PN"166"6;
"VSS70"
$PN"164"6;
"VSS69"
$PN"162"6;
"VSS68"
$PN"160"6;
"VSS67"
$PN"158"6;
"VSS66"
$PN"155"6;
"VSS65"
$PN"153"6;
"VSS64"
$PN"151"6;
"VSS63"
$PN"143"5;
"VSS59"
$PN"134"5;
"VSS57"
$PN"130"5;
"VSS56"
$PN"128"5;
"VSS55"
$PN"125"5;
"VSS54"
$PN"123"5;
"VSS53"
$PN"121"5;
"VSS52"
$PN"119"5;
"VSS51"
$PN"117"5;
"VSS50"
$PN"114"5;
"VSS49"
$PN"112"5;
"VSS48"
$PN"110"5;
"VSS47"
$PN"108"5;
"VSS46"
$PN"106"5;
"VSS45"
$PN"103"5;
"VSS44"
$PN"101"5;
"VSS43"
$PN"99"5;
"VSS42"
$PN"97"5;
"VSS41"
$PN"95"5;
"VSS40"
$PN"92"5;
"VSS39"
$PN"90"5;
"VSS38"
$PN"88"5;
"VSS37"
$PN"85"5;
"VSS36"
$PN"83"5;
"VSS35"
$PN"81"5;
"VSS34"
$PN"79"5;
"VSS33"
$PN"77"5;
"VSS32"
$PN"75"5;
"VSS31"
$PN"73"5;
"VSS30"
$PN"71"5;
"VSS29"
$PN"69"5;
"VSS28"
$PN"67"5;
"VSS27"
$PN"65"5;
"VSS26"
$PN"63"5;
"VSS25"
$PN"61"5;
"VSS24"
$PN"59"5;
"VSS23"
$PN"57"5;
"VSS22"
$PN"54"5;
"VSS21"
$PN"52"5;
"VSS20"
$PN"50"5;
"VSS19"
$PN"48"5;
"VSS18"
$PN"46"5;
"VSS17"
$PN"43"5;
"VSS16"
$PN"41"5;
"VSS15"
$PN"39"5;
"VSS14"
$PN"37"5;
"VSS13"
$PN"35"5;
"VSS12"
$PN"32"5;
"VSS11"
$PN"30"5;
"VSS10"
$PN"28"5;
"VSS9"
$PN"26"5;
"VSS8"
$PN"24"5;
"VSS7"
$PN"21"5;
"VSS6"
$PN"19"5;
"VSS5"
$PN"17"5;
"VSS4"
$PN"15"5;
"VSS3"
$PN"13"5;
"VSS2"
$PN"10"5;
"VSS1"
$PN"8"5;
"VSS0"
$PN"6"5;
%"UNIVERSAL_GND"
"1","(5275,275)","0","logical_power","I177";
;
CDS_LIB"logical_power"
HDL_POWER"GND";
"A"5;
%"SCONN288_ADR50017P130CC"
"2","(1000,2975)","0","pure_quanta","I178";
;
PART_NUMBER"DFHST8FS461"
PART_TYPE"SMLF"
VALUE"SCONN288_ADR50017-P130CC"
MATERIAL"IO"
LOCATION"J15"
NEEDS_NO_SIZE"TRUE"
CDS_LMAN_SYM_OUTLINE"-600,1150,600,-1150"
CDS_LIB"pure_quanta"
$SEC"2"
CDS_SEC"2";
"DQS7_A_C||TDQS7_A_C \B"
$PN"178"33;
"DQS6_A_T||TDQS6_A_T"
$PN"168"54;
"DQS8_B_T||TDQS8_B_T"
$PN"283"62;
"DQS8_B_C||TDQS8_B_C \B"
$PN"282"42;
"DQS7_B_T||TDQS7_B_T"
$PN"272"63;
"DQS0_A_C \B"
$PN"12"40;
"DQS0_A_T"
$PN"11"60;
"DQS0_B_C \B"
$PN"105"50;
"DQS0_B_T"
$PN"104"70;
"DQS1_A_C \B"
$PN"23"39;
"DQS1_A_T"
$PN"22"59;
"DQS1_B_C \B"
$PN"116"48;
"DQS1_B_T"
$PN"115"69;
"DQS2_A_C \B"
$PN"34"37;
"DQS2_A_T"
$PN"33"58;
"DQS2_B_C \B"
$PN"127"49;
"DQS2_B_T"
$PN"126"68;
"DQS3_A_C \B"
$PN"45"38;
"DQS3_A_T"
$PN"44"57;
"DQS3_B_C \B"
$PN"138"47;
"DQS3_B_T"
$PN"137"67;
"DQS4_A_C \B"
$PN"56"36;
"DQS4_A_T"
$PN"55"56;
"DQS4_B_C \B"
$PN"238"46;
"DQS4_B_T"
$PN"239"66;
"DQS5_A_C||TDQS5_A_C||DQS5_A_T||TDQS5_A_T \B"
$PN"156"35;
"DQS5_A_T||TDQS5_A_T"
$PN"157"55;
"DQS5_B_C||TDQS5_B_C \B"
$PN"249"45;
"DQS5_B_T||TDQS5_B_T"
$PN"250"65;
"DQS6_A_C||TDQS6_A_C||DQS6_A_T||TDQS6_A_T \B"
$PN"167"34;
"DQS6_B_C||TDQS6_B_C \B"
$PN"260"43;
"DQS6_B_T||TDQS6_B_T"
$PN"261"64;
"DQS7_A_T||TDQS7_A_T"
$PN"179"53;
"DQS7_B_C||TDQS7_B_C \B"
$PN"271"44;
"DQS8_A_C||TDQS8_A_C \B"
$PN"189"32;
"DQS8_A_T||TDQS8_A_T"
$PN"190"52;
"DQS9_A_C||TDQS9_A_C \B"
$PN"200"31;
"DQS9_A_T||TDQS9_A_T"
$PN"201"51;
"DQS9_B_C||TDQS9_B_C \B"
$PN"94"41;
"DQS9_B_T||TDQS9_B_T||DBI4_B_N"
$PN"93"61;
%"Q_RES"
"1","(-3450,1250)","0","pure_quanta","I179";
;
PART_NUMBER"CS04992FB07"
VALUE"49.9"
MATERIAL"CHIP"
$LOCATION"R3889"
CDS_LIB"pure_quanta"
PACK_TYPE"0402LF"
WATTAGE"1/16W"
TOLERANCE"1%"
CDS_LOCATION"R3889"
$SEC"1"
CDS_SEC"1";
"B"
$PN"2"27;
"A"
$PN"1"25;
%"VCC_CORE"
"1","(-3325,1850)","0","logical_power","I22";
;
HDL_POWER"P3V3_AUX"
CDS_LIB"logical_power";
"A"1;
%"TAP"
"1","(-2500,1775)","2","standard","I23";
;
CDS_LIB"standard"
BODY_TYPE"PLUMBING"
HDL_TAP"TRUE";
"B \NAC \NWC"11;
"S \NAC"
BN"0"151;
%"TAP"
"1","(-2500,1875)","2","standard","I24";
;
CDS_LIB"standard"
BODY_TYPE"PLUMBING"
HDL_TAP"TRUE";
"B \NAC \NWC"11;
"S \NAC"
BN"2"152;
%"TAP"
"1","(-2500,1825)","2","standard","I25";
;
CDS_LIB"standard"
BODY_TYPE"PLUMBING"
HDL_TAP"TRUE";
"B \NAC \NWC"11;
"S \NAC"
BN"1"30;
%"TAP"
"1","(-2500,1925)","2","standard","I26";
;
CDS_LIB"standard"
BODY_TYPE"PLUMBING"
HDL_TAP"TRUE";
"B \NAC \NWC"11;
"S \NAC"
BN"3"153;
%"TAP"
"1","(-2500,2025)","2","standard","I27";
;
CDS_LIB"standard"
BODY_TYPE"PLUMBING"
HDL_TAP"TRUE";
"B \NAC \NWC"11;
"S \NAC"
BN"5"154;
%"TAP"
"1","(-2500,1975)","2","standard","I28";
;
CDS_LIB"standard"
BODY_TYPE"PLUMBING"
HDL_TAP"TRUE";
"B \NAC \NWC"11;
"S \NAC"
BN"4"71;
%"TAP"
"1","(-2500,2075)","2","standard","I29";
;
CDS_LIB"standard"
BODY_TYPE"PLUMBING"
HDL_TAP"TRUE";
"B \NAC \NWC"11;
"S \NAC"
BN"6"155;
%"TAP"
"1","(-2500,2125)","2","standard","I30";
;
CDS_LIB"standard"
BODY_TYPE"PLUMBING"
HDL_TAP"TRUE";
"B \NAC \NWC"11;
"S \NAC"
BN"7"174;
%"TAP"
"1","(-2500,2275)","2","standard","I31";
;
CDS_LIB"standard"
BODY_TYPE"PLUMBING"
HDL_TAP"TRUE";
"B \NAC \NWC"10;
"S \NAC"
BN"1"175;
%"TAP"
"1","(-2500,2375)","2","standard","I32";
;
CDS_LIB"standard"
BODY_TYPE"PLUMBING"
HDL_TAP"TRUE";
"B \NAC \NWC"10;
"S \NAC"
BN"3"158;
%"TAP"
"1","(-2500,2325)","2","standard","I33";
;
CDS_LIB"standard"
BODY_TYPE"PLUMBING"
HDL_TAP"TRUE";
"B \NAC \NWC"10;
"S \NAC"
BN"2"157;
%"TAP"
"1","(-2500,2225)","2","standard","I34";
;
CDS_LIB"standard"
BODY_TYPE"PLUMBING"
HDL_TAP"TRUE";
"B \NAC \NWC"10;
"S \NAC"
BN"0"156;
%"TAP"
"1","(-2500,2425)","2","standard","I35";
;
CDS_LIB"standard"
BODY_TYPE"PLUMBING"
HDL_TAP"TRUE";
"B \NAC \NWC"10;
"S \NAC"
BN"4"176;
%"TAP"
"1","(-2500,2525)","2","standard","I36";
;
CDS_LIB"standard"
BODY_TYPE"PLUMBING"
HDL_TAP"TRUE";
"B \NAC \NWC"10;
"S \NAC"
BN"6"76;
%"TAP"
"1","(-2500,2575)","2","standard","I37";
;
CDS_LIB"standard"
BODY_TYPE"PLUMBING"
HDL_TAP"TRUE";
"B \NAC \NWC"10;
"S \NAC"
BN"7"177;
%"TAP"
"1","(-2500,2475)","2","standard","I38";
;
CDS_LIB"standard"
BODY_TYPE"PLUMBING"
HDL_TAP"TRUE";
"B \NAC \NWC"10;
"S \NAC"
BN"5"159;
%"TAP"
"1","(-2500,3425)","2","standard","I39";
;
CDS_LIB"standard"
BODY_TYPE"PLUMBING"
HDL_TAP"TRUE";
"B \NAC \NWC"13;
"S \NAC"
BN"3"166;
%"TAP"
"1","(-2500,3325)","2","standard","I40";
;
CDS_LIB"standard"
BODY_TYPE"PLUMBING"
HDL_TAP"TRUE";
"B \NAC \NWC"13;
"S \NAC"
BN"1"170;
%"TAP"
"1","(-2500,3375)","2","standard","I41";
;
CDS_LIB"standard"
BODY_TYPE"PLUMBING"
HDL_TAP"TRUE";
"B \NAC \NWC"13;
"S \NAC"
BN"2"168;
%"TAP"
"1","(-2500,3275)","2","standard","I42";
;
CDS_LIB"standard"
BODY_TYPE"PLUMBING"
HDL_TAP"TRUE";
"B \NAC \NWC"13;
"S \NAC"
BN"0"172;
%"TAP"
"1","(-2500,3575)","2","standard","I43";
;
CDS_LIB"standard"
BODY_TYPE"PLUMBING"
HDL_TAP"TRUE";
"B \NAC \NWC"13;
"S \NAC"
BN"6"160;
%"TAP"
"1","(-2500,3525)","2","standard","I44";
;
CDS_LIB"standard"
BODY_TYPE"PLUMBING"
HDL_TAP"TRUE";
"B \NAC \NWC"13;
"S \NAC"
BN"5"162;
%"TAP"
"1","(-2500,3475)","2","standard","I45";
;
CDS_LIB"standard"
BODY_TYPE"PLUMBING"
HDL_TAP"TRUE";
"B \NAC \NWC"13;
"S \NAC"
BN"4"164;
%"TAP"
"1","(-2500,3675)","2","standard","I46";
;
CDS_LIB"standard"
BODY_TYPE"PLUMBING"
HDL_TAP"TRUE";
"B \NAC \NWC"12;
"S \NAC"
BN"0"173;
%"Q_RES"
"2","(-2275,-175)","0","pure_quanta","I47";
;
PART_NUMBER"CS41272FB07"
VALUE"127K"
MATERIAL"CHIP"
TOLERANCE"1%"
PACK_TYPE"0402LF"
WATTAGE"1/16W"
$LOCATION"R40"
CDS_LIB"pure_quanta"
CDS_LOCATION"R40"
$SEC"1"
CDS_SEC"1";
"A"
$PN"1"178;
"B"
$PN"2"9;
%"SCONN288_ADR50017P130CC"
"1","(-1675,2250)","0","pure_quanta","I48";
;
PART_NUMBER"DFHST8FS461"
MATERIAL"IO"
PART_TYPE"SMLF"
VALUE"SCONN288_ADR50017-P130CC"
$LOCATION"J15"
NEEDS_NO_SIZE"TRUE"
CDS_LMAN_SYM_OUTLINE"-450,1875,450,-1875"
CDS_LIB"pure_quanta"
CDS_LOCATION"J15"
$SEC"1"
CDS_SEC"1";
"DQ31_A"
$PN"194"72;
"CB7_A"
$PN"205"177;
"CB4_A"
$PN"58"176;
"CB1_A"
$PN"53"175;
"CB7_B"
$PN"236"174;
"ALERT_N \B"
$PN"62"22;
"CA0_A"
$PN"66"173;
"CA0_B"
$PN"76"172;
"CA1_A"
$PN"211"171;
"CA1_B"
$PN"221"170;
"CA2_A"
$PN"68"169;
"CA2_B"
$PN"78"168;
"CA3_A"
$PN"213"167;
"CA3_B"
$PN"223"166;
"CA4_A"
$PN"70"165;
"CA4_B"
$PN"80"164;
"CA5_A"
$PN"215"163;
"CA5_B"
$PN"225"162;
"CA6_A"
$PN"72"161;
"CA6_B"
$PN"82"160;
"CB6_A"
$PN"203"76;
"CB5_A"
$PN"60"159;
"CB3_A"
$PN"198"158;
"CB2_A"
$PN"196"157;
"CB0_A"
$PN"51"156;
"CB6_B"
$PN"234"155;
"CB5_B"
$PN"91"154;
"CB4_B"
$PN"89"71;
"CB3_B"
$PN"243"153;
"CB2_B"
$PN"241"152;
"CB1_B"
$PN"98"30;
"CB0_B"
$PN"96"151;
"CK_C \B"
$PN"218"21;
"CK_T"
$PN"217"150;
"CS0_A_N"
$PN"64"149;
"CS0_B_N"
$PN"84"148;
"CS1_A_N"
$PN"209"147;
"CS1_B_N"
$PN"229"146;
"DQ30_A"
$PN"192"145;
"DQ29_A"
$PN"49"144;
"DQ28_A"
$PN"47"73;
"DQ27_A"
$PN"187"143;
"DQ26_A"
$PN"185"142;
"DQ25_A"
$PN"42"141;
"DQ24_A"
$PN"40"140;
"DQ23_A"
$PN"183"139;
"DQ22_A"
$PN"181"138;
"DQ21_A"
$PN"38"137;
"DQ20_A"
$PN"36"136;
"DQ19_A"
$PN"176"74;
"DQ18_A"
$PN"174"135;
"DQ17_A"
$PN"31"134;
"DQ16_A"
$PN"29"133;
"DQ15_A"
$PN"172"132;
"DQ14_A"
$PN"170"79;
"DQ13_A"
$PN"27"80;
"DQ12_A"
$PN"25"131;
"DQ11_A"
$PN"165"130;
"DQ10_A"
$PN"163"78;
"DQ9_A"
$PN"20"77;
"DQ8_A"
$PN"18"129;
"DQ7_A"
$PN"161"128;
"DQ6_A"
$PN"159"127;
"DQ5_A"
$PN"16"126;
"DQ4_A"
$PN"14"75;
"DQ3_A"
$PN"154"81;
"DQ2_A"
$PN"152"82;
"DQ1_A"
$PN"9"83;
"DQ0_A"
$PN"7"125;
"DQ31_B"
$PN"287"124;
"DQ30_B"
$PN"285"84;
"DQ29_B"
$PN"142"20;
"DQ28_B"
$PN"140"123;
"DQ27_B"
$PN"280"122;
"DQ26_B"
$PN"278"121;
"DQ25_B"
$PN"135"120;
"DQ24_B"
$PN"133"119;
"DQ23_B"
$PN"276"118;
"DQ22_B"
$PN"274"117;
"DQ21_B"
$PN"131"116;
"DQ20_B"
$PN"129"115;
"DQ19_B"
$PN"269"114;
"DQ18_B"
$PN"267"113;
"DQ17_B"
$PN"124"112;
"DQ16_B"
$PN"122"111;
"DQ15_B"
$PN"265"110;
"DQ14_B"
$PN"263"109;
"DQ13_B"
$PN"120"108;
"DQ12_B"
$PN"118"107;
"DQ11_B"
$PN"258"106;
"DQ10_B"
$PN"256"105;
"DQ9_B"
$PN"113"104;
"DQ8_B"
$PN"111"103;
"DQ7_B"
$PN"254"102;
"DQ6_B"
$PN"252"101;
"DQ5_B"
$PN"109"100;
"DQ4_B"
$PN"107"99;
"DQ3_B"
$PN"247"98;
"DQ2_B"
$PN"245"97;
"DQ1_B"
$PN"102"96;
"DQ0_B"
$PN"100"95;
"HSA"
$PN"148"23;
"HSCL"
$PN"4"25;
"HSDA"
$PN"5"24;
"LBD||RSP_A_N"
$PN"86"94;
"LBS||RSP_B_N"
$PN"87"93;
"PAR_A"
$PN"74"92;
"PAR_B"
$PN"227"91;
"PWR_GOOD||FAIL_N"
$PN"147"28;
"RESET_N \B"
$PN"207"26;
"RFU6"
$PN"232"29;
"RFU5"
$PN"231"90;
"RFU4"
$PN"220"89;
"RFU3"
$PN"150"88;
"RFU2"
$PN"149"87;
"RFU1"
$PN"144"86;
"RFU0"
$PN"2"85;
"VIN_MGMT"
$PN"3"1;
%"TAP"
"1","(-850,775)","0","standard","I49";
;
CDS_LIB"standard"
BODY_TYPE"PLUMBING"
HDL_TAP"TRUE";
"B \NAC \NWC"15;
"S \NAC"
BN"0"95;
%"TAP"
"1","(-850,875)","0","standard","I50";
;
CDS_LIB"standard"
BODY_TYPE"PLUMBING"
HDL_TAP"TRUE";
"B \NAC \NWC"15;
"S \NAC"
BN"2"97;
%"TAP"
"1","(-850,825)","0","standard","I51";
;
CDS_LIB"standard"
BODY_TYPE"PLUMBING"
HDL_TAP"TRUE";
"B \NAC \NWC"15;
"S \NAC"
BN"1"96;
%"TAP"
"1","(-850,925)","0","standard","I52";
;
CDS_LIB"standard"
BODY_TYPE"PLUMBING"
HDL_TAP"TRUE";
"B \NAC \NWC"15;
"S \NAC"
BN"3"98;
%"TAP"
"1","(-850,1025)","0","standard","I53";
;
CDS_LIB"standard"
BODY_TYPE"PLUMBING"
HDL_TAP"TRUE";
"B \NAC \NWC"15;
"S \NAC"
BN"5"100;
%"TAP"
"1","(-850,975)","0","standard","I54";
;
CDS_LIB"standard"
BODY_TYPE"PLUMBING"
HDL_TAP"TRUE";
"B \NAC \NWC"15;
"S \NAC"
BN"4"99;
%"TAP"
"1","(-850,1075)","0","standard","I55";
;
CDS_LIB"standard"
BODY_TYPE"PLUMBING"
HDL_TAP"TRUE";
"B \NAC \NWC"15;
"S \NAC"
BN"6"101;
%"TAP"
"1","(-850,1125)","0","standard","I56";
;
CDS_LIB"standard"
BODY_TYPE"PLUMBING"
HDL_TAP"TRUE";
"B \NAC \NWC"15;
"S \NAC"
BN"7"102;
%"TAP"
"1","(-850,1175)","0","standard","I57";
;
CDS_LIB"standard"
BODY_TYPE"PLUMBING"
HDL_TAP"TRUE";
"B \NAC \NWC"15;
"S \NAC"
BN"8"103;
%"TAP"
"1","(-850,1225)","0","standard","I58";
;
CDS_LIB"standard"
BODY_TYPE"PLUMBING"
HDL_TAP"TRUE";
"B \NAC \NWC"15;
"S \NAC"
BN"9"104;
%"TAP"
"1","(-850,1275)","0","standard","I59";
;
CDS_LIB"standard"
BODY_TYPE"PLUMBING"
HDL_TAP"TRUE";
"B \NAC \NWC"15;
"S \NAC"
BN"10"105;
%"TAP"
"1","(-850,1375)","0","standard","I60";
;
CDS_LIB"standard"
BODY_TYPE"PLUMBING"
HDL_TAP"TRUE";
"B \NAC \NWC"15;
"S \NAC"
BN"12"107;
%"TAP"
"1","(-850,1325)","0","standard","I61";
;
CDS_LIB"standard"
BODY_TYPE"PLUMBING"
HDL_TAP"TRUE";
"B \NAC \NWC"15;
"S \NAC"
BN"11"106;
%"TAP"
"1","(-850,1425)","0","standard","I62";
;
CDS_LIB"standard"
BODY_TYPE"PLUMBING"
HDL_TAP"TRUE";
"B \NAC \NWC"15;
"S \NAC"
BN"13"108;
%"TAP"
"1","(-850,1475)","0","standard","I63";
;
CDS_LIB"standard"
BODY_TYPE"PLUMBING"
HDL_TAP"TRUE";
"B \NAC \NWC"15;
"S \NAC"
BN"14"109;
%"TAP"
"1","(-850,1525)","0","standard","I64";
;
CDS_LIB"standard"
BODY_TYPE"PLUMBING"
HDL_TAP"TRUE";
"B \NAC \NWC"15;
"S \NAC"
BN"15"110;
%"TAP"
"1","(-850,1625)","0","standard","I65";
;
CDS_LIB"standard"
BODY_TYPE"PLUMBING"
HDL_TAP"TRUE";
"B \NAC \NWC"15;
"S \NAC"
BN"17"112;
%"TAP"
"1","(-850,1575)","0","standard","I66";
;
CDS_LIB"standard"
BODY_TYPE"PLUMBING"
HDL_TAP"TRUE";
"B \NAC \NWC"15;
"S \NAC"
BN"16"111;
%"TAP"
"1","(-850,1725)","0","standard","I67";
;
CDS_LIB"standard"
BODY_TYPE"PLUMBING"
HDL_TAP"TRUE";
"B \NAC \NWC"15;
"S \NAC"
BN"19"114;
%"TAP"
"1","(-850,1675)","0","standard","I68";
;
CDS_LIB"standard"
BODY_TYPE"PLUMBING"
HDL_TAP"TRUE";
"B \NAC \NWC"15;
"S \NAC"
BN"18"113;
%"TAP"
"1","(-850,1775)","0","standard","I69";
;
CDS_LIB"standard"
BODY_TYPE"PLUMBING"
HDL_TAP"TRUE";
"B \NAC \NWC"15;
"S \NAC"
BN"20"115;
%"TAP"
"1","(-850,1825)","0","standard","I70";
;
CDS_LIB"standard"
BODY_TYPE"PLUMBING"
HDL_TAP"TRUE";
"B \NAC \NWC"15;
"S \NAC"
BN"21"116;
%"TAP"
"1","(-850,1875)","0","standard","I71";
;
CDS_LIB"standard"
BODY_TYPE"PLUMBING"
HDL_TAP"TRUE";
"B \NAC \NWC"15;
"S \NAC"
BN"22"117;
%"TAP"
"1","(-850,1925)","0","standard","I72";
;
CDS_LIB"standard"
BODY_TYPE"PLUMBING"
HDL_TAP"TRUE";
"B \NAC \NWC"15;
"S \NAC"
BN"23"118;
%"TAP"
"1","(-850,1975)","0","standard","I73";
;
CDS_LIB"standard"
BODY_TYPE"PLUMBING"
HDL_TAP"TRUE";
"B \NAC \NWC"15;
"S \NAC"
BN"24"119;
%"TAP"
"1","(-850,2025)","0","standard","I74";
;
CDS_LIB"standard"
BODY_TYPE"PLUMBING"
HDL_TAP"TRUE";
"B \NAC \NWC"15;
"S \NAC"
BN"25"120;
%"TAP"
"1","(-850,2075)","0","standard","I75";
;
CDS_LIB"standard"
BODY_TYPE"PLUMBING"
HDL_TAP"TRUE";
"B \NAC \NWC"15;
"S \NAC"
BN"26"121;
%"TAP"
"1","(-850,2125)","0","standard","I76";
;
CDS_LIB"standard"
BODY_TYPE"PLUMBING"
HDL_TAP"TRUE";
"B \NAC \NWC"15;
"S \NAC"
BN"27"122;
%"TAP"
"1","(-850,2175)","0","standard","I77";
;
CDS_LIB"standard"
BODY_TYPE"PLUMBING"
HDL_TAP"TRUE";
"B \NAC \NWC"15;
"S \NAC"
BN"28"123;
%"TAP"
"1","(-850,2225)","0","standard","I78";
;
CDS_LIB"standard"
BODY_TYPE"PLUMBING"
HDL_TAP"TRUE";
"B \NAC \NWC"15;
"S \NAC"
BN"29"20;
%"TAP"
"1","(-850,2275)","0","standard","I79";
;
CDS_LIB"standard"
BODY_TYPE"PLUMBING"
HDL_TAP"TRUE";
"B \NAC \NWC"15;
"S \NAC"
BN"30"84;
%"TAP"
"1","(-850,2325)","0","standard","I80";
;
CDS_LIB"standard"
BODY_TYPE"PLUMBING"
HDL_TAP"TRUE";
"B \NAC \NWC"15;
"S \NAC"
BN"31"124;
%"TAP"
"1","(-850,2425)","0","standard","I81";
;
CDS_LIB"standard"
BODY_TYPE"PLUMBING"
HDL_TAP"TRUE";
"B \NAC \NWC"14;
"S \NAC"
BN"0"125;
%"TAP"
"1","(-850,2525)","0","standard","I82";
;
CDS_LIB"standard"
BODY_TYPE"PLUMBING"
HDL_TAP"TRUE";
"B \NAC \NWC"14;
"S \NAC"
BN"2"82;
%"TAP"
"1","(-850,2475)","0","standard","I83";
;
CDS_LIB"standard"
BODY_TYPE"PLUMBING"
HDL_TAP"TRUE";
"B \NAC \NWC"14;
"S \NAC"
BN"1"83;
%"TAP"
"1","(-850,2575)","0","standard","I84";
;
CDS_LIB"standard"
BODY_TYPE"PLUMBING"
HDL_TAP"TRUE";
"B \NAC \NWC"14;
"S \NAC"
BN"3"81;
%"TAP"
"1","(-850,2625)","0","standard","I85";
;
CDS_LIB"standard"
BODY_TYPE"PLUMBING"
HDL_TAP"TRUE";
"B \NAC \NWC"14;
"S \NAC"
BN"4"75;
%"TAP"
"1","(-850,2675)","0","standard","I86";
;
CDS_LIB"standard"
BODY_TYPE"PLUMBING"
HDL_TAP"TRUE";
"B \NAC \NWC"14;
"S \NAC"
BN"5"126;
%"TAP"
"1","(-850,2775)","0","standard","I87";
;
CDS_LIB"standard"
BODY_TYPE"PLUMBING"
HDL_TAP"TRUE";
"B \NAC \NWC"14;
"S \NAC"
BN"7"128;
%"TAP"
"1","(-850,2725)","0","standard","I88";
;
CDS_LIB"standard"
BODY_TYPE"PLUMBING"
HDL_TAP"TRUE";
"B \NAC \NWC"14;
"S \NAC"
BN"6"127;
%"TAP"
"1","(-850,2825)","0","standard","I89";
;
CDS_LIB"standard"
BODY_TYPE"PLUMBING"
HDL_TAP"TRUE";
"B \NAC \NWC"14;
"S \NAC"
BN"8"129;
%"TAP"
"1","(-850,2875)","0","standard","I90";
;
CDS_LIB"standard"
BODY_TYPE"PLUMBING"
HDL_TAP"TRUE";
"B \NAC \NWC"14;
"S \NAC"
BN"9"77;
%"TAP"
"1","(-850,2925)","0","standard","I91";
;
CDS_LIB"standard"
BODY_TYPE"PLUMBING"
HDL_TAP"TRUE";
"B \NAC \NWC"14;
"S \NAC"
BN"10"78;
%"TAP"
"1","(-850,2975)","0","standard","I92";
;
CDS_LIB"standard"
BODY_TYPE"PLUMBING"
HDL_TAP"TRUE";
"B \NAC \NWC"14;
"S \NAC"
BN"11"130;
%"TAP"
"1","(-850,3025)","0","standard","I93";
;
CDS_LIB"standard"
BODY_TYPE"PLUMBING"
HDL_TAP"TRUE";
"B \NAC \NWC"14;
"S \NAC"
BN"12"131;
%"TAP"
"1","(-850,3075)","0","standard","I94";
;
CDS_LIB"standard"
BODY_TYPE"PLUMBING"
HDL_TAP"TRUE";
"B \NAC \NWC"14;
"S \NAC"
BN"13"80;
%"TAP"
"1","(-850,3125)","0","standard","I95";
;
CDS_LIB"standard"
BODY_TYPE"PLUMBING"
HDL_TAP"TRUE";
"B \NAC \NWC"14;
"S \NAC"
BN"14"79;
%"TAP"
"1","(-850,3175)","0","standard","I96";
;
CDS_LIB"standard"
BODY_TYPE"PLUMBING"
HDL_TAP"TRUE";
"B \NAC \NWC"14;
"S \NAC"
BN"15"132;
%"TAP"
"1","(-850,3225)","0","standard","I97";
;
CDS_LIB"standard"
BODY_TYPE"PLUMBING"
HDL_TAP"TRUE";
"B \NAC \NWC"14;
"S \NAC"
BN"16"133;
%"TAP"
"1","(-850,3275)","0","standard","I98";
;
CDS_LIB"standard"
BODY_TYPE"PLUMBING"
HDL_TAP"TRUE";
"B \NAC \NWC"14;
"S \NAC"
BN"17"134;
%"TAP"
"1","(-850,3325)","0","standard","I99";
;
CDS_LIB"standard"
BODY_TYPE"PLUMBING"
HDL_TAP"TRUE";
"B \NAC \NWC"14;
"S \NAC"
BN"18"135;
END.
